#ISCELL
  mstr_misc dns *
  *
#ISCELL
  mstr_symbols design_note *
  *
#ISCELL
  mstr_symbols intel_corp_bpage *
  *
#CELL
  mstr_discrete res *
  page125_i11
#ISCELL
  mstr_symbols gnd *
  page125_i14
#ISCELL
  mstr_symbols gnd *
  page125_i16
#ISCELL
  mstr_standard offpage *
  page125_i20
#CELL
  mstr_discrete res *
  page125_i21
#ISCELL
  mstr_standard offpage *
  page125_i23
#CELL
  mstr_discrete res *
  page125_i24
#ISCELL
  mstr_symbols gnd *
  page125_i25
#CELL
  mstr_discrete res *
  page125_i40
#CELL
  mstr_discrete res *
  page125_i41
#ISCELL
  mstr_standard offpage *
  page125_i43
#ISCELL
  mstr_symbols p3v3_stby *
  page125_i48
#ISCELL
  mstr_symbols p3v3_stby *
  page125_i49
#CELL
  mstr_discrete res *
  page125_i50
#ISCELL
  mstr_symbols p3v3_stby *
  page125_i51
#ISCELL
  mstr_standard offpage *
  page125_i53
#ISCELL
  mstr_symbols gnd *
  page125_i54
#ISCELL
  mstr_symbols gnd *
  page125_i6
#CELL
  mstr_discrete res *
  page125_i60
#ISCELL
  mstr_symbols p3v3_stby *
  page125_i61
#ISCELL
  mstr_standard offpage *
  page125_i64
#ISCELL
  mstr_standard offpage *
  page125_i65
#ISCELL
  mstr_symbols p3v3_stby *
  page125_i66
#ISCELL
  mstr_symbols gnd *
  page125_i69
#ISCELL
  mstr_standard offpage *
  page125_i7
#CELL
  mstr_discrete res *
  page125_i72
#ISCELL
  mstr_standard offpage *
  page125_i73
#ISCELL
  mstr_symbols p3v3_stby *
  page125_i74
#ISCELL
  mstr_symbols p3v3_stby *
  page125_i75
#ISCELL
  mstr_standard offpage *
  page125_i77
#CELL
  mstr_discrete res *
  page125_i78
#ISCELL
  mstr_symbols p3v3_stby *
  page125_i79
#ISCELL
  mstr_standard offpage *
  page125_i82
#CELL
  mstr_discrete res *
  page125_i83
#ISCELL
  mstr_symbols p3v3_stby *
  page125_i84
#CELL
  mstr_discrete res *
  page125_i85
#CELL
  mstr_discrete res *
  page125_i86
#CELL
  mstr_discrete res *
  page125_i87
#CELL
  mstr_discrete res *
  page125_i88
#CELL
  mstr_discrete res *
  page125_i89
